# T6G (Grand Teton) — schematic netlist excerpt (pin names and nets, part order shuffled) for the footprints in the layout excerpt that follows; sources: Cadence DE-HDL packaged netlist, KiCad conversion of 04192023_DAF0TMB3IC0_F0TG_MB_C_brd_V02_OCP.brd

C8006  Q_CAP  0.1UF 25V 10% X7R  pkg 0402  page 172 : A = JTAG_BMC_R_D_OE ; B = GND
R3589  Q_RES  33.2 1% CHIP  pkg 0402LF  page 251 : A = SMB_INA230_3V3AUX_SDA ; B = SMB_INA230_2_3V3AUX_SDA_R

(kicad_pcb
	(version 20260206)
	(generator "pcbnew")
	(generator_version "10.0")
	(general
		(thickness 1.6)
		(legacy_teardrops no)
	)
	(paper "A4")
	(title_block
		(title "04192023_DAF0TMB3IC0_F0TG_MB_C_brd_V02_OCP.brd")
		(comment 1 "Grand Teton / footprints 3766-3767 of 8354")
	)
	(layers
		(0 "F.Cu" signal "TOP")
		(4 "In1.Cu" signal "GND")
		(6 "In2.Cu" signal "IN1")
		(8 "In3.Cu" signal "GND1")
		(10 "In4.Cu" signal "IN2")
		(12 "In5.Cu" signal "GND2")
		(14 "In6.Cu" signal "IN3")
		(16 "In7.Cu" signal "GND3")
		(18 "In8.Cu" signal "VCC")
		(20 "In9.Cu" signal "VCC1")
		(22 "In10.Cu" signal "GND4")
		(24 "In11.Cu" signal "IN4")
		(26 "In12.Cu" signal "GND5")
		(28 "In13.Cu" signal "IN5")
		(30 "In14.Cu" signal "GND6")
		(32 "In15.Cu" signal "IN6")
		(34 "In16.Cu" signal "GND7")
		(2 "B.Cu" signal "BOTTOM")
		(9 "F.Adhes" user "F.Adhesive")
		(11 "B.Adhes" user "B.Adhesive")
		(13 "F.Paste" user "Package Geometry/Pastemask Top")
		(15 "B.Paste" user "Package Geometry/Pastemask Bottom")
		(5 "F.SilkS" user "Ref Des/Silkscreen Top")
		(7 "B.SilkS" user "Ref Des/Silkscreen Bottom")
		(1 "F.Mask" user "Board Geometry/Soldermask Top")
		(3 "B.Mask" user "Board Geometry/Soldermask Bottom")
		(17 "Dwgs.User" user "User.Drawings")
		(19 "Cmts.User" user "User.Comments")
		(21 "Eco1.User" user "User.Eco1")
		(23 "Eco2.User" user "User.Eco2")
		(25 "Edge.Cuts" user "Board Geometry/Outline")
		(27 "Margin" user)
		(31 "F.CrtYd" user "Package Geometry/Place Bound Top")
		(29 "B.CrtYd" user "Package Geometry/Place Bound Bottom")
		(35 "F.Fab" user "Ref Des/Assembly Top")
		(33 "B.Fab" user "Ref Des/Assembly Bottom")
	)
	(footprint ""
		(layer "F.Cu")
		(at 259.842 -102.108 180)
		(property "Reference" "C8006"
			(at 0 0 180)
			(layer "F.SilkS")
			(hide yes)
			(effects
				(font
					(size 1.27 1.27)
				)
			)
		)
		(property "Value" ""
			(at 0 0 180)
			(layer "F.Fab")
			(effects
				(font
					(size 1.27 1.27)
				)
			)
		)
		(duplicate_pad_numbers_are_jumpers no)
		(fp_line
			(start 0.7874 0.4064)
			(end -0.7874 0.4064)
			(stroke
				(width 0.1524)
				(type default)
			)
			(layer "F.SilkS")
		)
		(fp_line
			(start 0.7874 -0.4064)
			(end 0.7874 0.4064)
			(stroke
				(width 0.1524)
				(type default)
			)
			(layer "F.SilkS")
		)
		(fp_line
			(start -0.7874 0.4064)
			(end -0.7874 -0.4064)
			(stroke
				(width 0.1524)
				(type default)
			)
			(layer "F.SilkS")
		)
		(fp_line
			(start -0.7874 -0.4064)
			(end 0.7874 -0.4064)
			(stroke
				(width 0.1524)
				(type default)
			)
			(layer "F.SilkS")
		)
		(fp_line
			(start 0.67945 0.3048)
			(end 0.120396 0.3048)
			(stroke
				(width 0.1)
				(type default)
			)
			(layer "F.Fab")
		)
		(fp_line
			(start 0.67945 -0.3048)
			(end 0.67945 0.3048)
			(stroke
				(width 0.1)
				(type default)
			)
			(layer "F.Fab")
		)
		(fp_line
			(start 0.12065 -0.2794)
			(end 0.12065 -0.3048)
			(stroke
				(width 0.1)
				(type default)
			)
			(layer "F.Fab")
		)
		(fp_line
			(start 0.12065 -0.3048)
			(end 0.67945 -0.3048)
			(stroke
				(width 0.1)
				(type default)
			)
			(layer "F.Fab")
		)
		(fp_line
			(start 0.120396 0.3048)
			(end 0.120396 0.2794)
			(stroke
				(width 0.1)
				(type default)
			)
			(layer "F.Fab")
		)
		(fp_line
			(start 0.120396 0.2794)
			(end -0.12065 0.2794)
			(stroke
				(width 0.1)
				(type default)
			)
			(layer "F.Fab")
		)
		(fp_line
			(start -0.12065 0.3048)
			(end -0.67945 0.3048)
			(stroke
				(width 0.1)
				(type default)
			)
			(layer "F.Fab")
		)
		(fp_line
			(start -0.12065 0.2794)
			(end -0.12065 0.3048)
			(stroke
				(width 0.1)
				(type default)
			)
			(layer "F.Fab")
		)
		(fp_line
			(start -0.12065 -0.2794)
			(end 0.12065 -0.2794)
			(stroke
				(width 0.1)
				(type default)
			)
			(layer "F.Fab")
		)
		(fp_line
			(start -0.12065 -0.305054)
			(end -0.12065 -0.2794)
			(stroke
				(width 0.1)
				(type default)
			)
			(layer "F.Fab")
		)
		(fp_line
			(start -0.67945 0.3048)
			(end -0.67945 -0.305054)
			(stroke
				(width 0.1)
				(type default)
			)
			(layer "F.Fab")
		)
		(fp_line
			(start -0.67945 -0.305054)
			(end -0.12065 -0.305054)
			(stroke
				(width 0.1)
				(type default)
			)
			(layer "F.Fab")
		)
		(pad "1" smd circle
			(at -0.40005 0 180)
			(size 0 0)
			(layers "F.Cu" "F.Mask" "F.Paste")
			(net "JTAG_BMC_R_D_OE")
		)
		(pad "2" smd circle
			(at 0.40005 0 180)
			(size 0 0)
			(layers "F.Cu" "F.Mask" "F.Paste")
			(net "GND")
		)
	)
	(footprint ""
		(layer "F.Cu")
		(at 213.416134 -47.335948 90)
		(property "Reference" "R3589"
			(at 0 0 90)
			(layer "F.SilkS")
			(hide yes)
			(effects
				(font
					(size 1.27 1.27)
				)
			)
		)
		(property "Value" ""
			(at 0 0 90)
			(layer "F.Fab")
			(effects
				(font
					(size 1.27 1.27)
				)
			)
		)
		(duplicate_pad_numbers_are_jumpers no)
		(fp_line
			(start 0.7874 -0.4064)
			(end 0.7874 0.4064)
			(stroke
				(width 0.1524)
				(type default)
			)
			(layer "F.SilkS")
		)
		(fp_line
			(start -0.7874 -0.4064)
			(end 0.7874 -0.4064)
			(stroke
				(width 0.1524)
				(type default)
			)
			(layer "F.SilkS")
		)
		(fp_line
			(start 0.7874 0.4064)
			(end -0.7874 0.4064)
			(stroke
				(width 0.1524)
				(type default)
			)
			(layer "F.SilkS")
		)
		(fp_line
			(start -0.7874 0.4064)
			(end -0.7874 -0.4064)
			(stroke
				(width 0.1524)
				(type default)
			)
			(layer "F.SilkS")
		)
		(fp_line
			(start -0.12065 -0.305054)
			(end -0.12065 -0.2794)
			(stroke
				(width 0.1)
				(type default)
			)
			(layer "F.Fab")
		)
		(fp_line
			(start -0.67945 -0.305054)
			(end -0.12065 -0.305054)
			(stroke
				(width 0.1)
				(type default)
			)
			(layer "F.Fab")
		)
		(fp_line
			(start 0.67945 -0.3048)
			(end 0.67945 0.3048)
			(stroke
				(width 0.1)
				(type default)
			)
			(layer "F.Fab")
		)
		(fp_line
			(start 0.12065 -0.3048)
			(end 0.67945 -0.3048)
			(stroke
				(width 0.1)
				(type default)
			)
			(layer "F.Fab")
		)
		(fp_line
			(start 0.12065 -0.2794)
			(end 0.12065 -0.3048)
			(stroke
				(width 0.1)
				(type default)
			)
			(layer "F.Fab")
		)
		(fp_line
			(start -0.12065 -0.2794)
			(end 0.12065 -0.2794)
			(stroke
				(width 0.1)
				(type default)
			)
			(layer "F.Fab")
		)
		(fp_line
			(start 0.120396 0.2794)
			(end -0.12065 0.2794)
			(stroke
				(width 0.1)
				(type default)
			)
			(layer "F.Fab")
		)
		(fp_line
			(start -0.12065 0.2794)
			(end -0.12065 0.3048)
			(stroke
				(width 0.1)
				(type default)
			)
			(layer "F.Fab")
		)
		(fp_line
			(start 0.67945 0.3048)
			(end 0.120396 0.3048)
			(stroke
				(width 0.1)
				(type default)
			)
			(layer "F.Fab")
		)
		(fp_line
			(start 0.120396 0.3048)
			(end 0.120396 0.2794)
			(stroke
				(width 0.1)
				(type default)
			)
			(layer "F.Fab")
		)
		(fp_line
			(start -0.12065 0.3048)
			(end -0.67945 0.3048)
			(stroke
				(width 0.1)
				(type default)
			)
			(layer "F.Fab")
		)
		(fp_line
			(start -0.67945 0.3048)
			(end -0.67945 -0.305054)
			(stroke
				(width 0.1)
				(type default)
			)
			(layer "F.Fab")
		)
		(pad "1" smd circle
			(at -0.40005 0 90)
			(size 0 0)
			(layers "F.Cu" "F.Mask" "F.Paste")
			(net "SMB_INA230_3V3AUX_SDA")
		)
		(pad "2" smd circle
			(at 0.40005 0 90)
			(size 0 0)
			(layers "F.Cu" "F.Mask" "F.Paste")
			(net "SMB_INA230_2_3V3AUX_SDA_R")
		)
	)
)
